(kicad_pcb
	(version 20260206)
	(generator "pcbnew")
	(generator_version "10.0")
	(general
		(thickness 1.6)
		(legacy_teardrops no)
	)
	(paper "A4")
	(title_block
		(title "panther-plus-userver — 13130-1b_20150205.brd")
		(comment 1 "Honey Badger (Wiwynn) / footprints 261-269 of 1509")
	)
	(layers
		(0 "F.Cu" signal "TOP")
		(4 "In1.Cu" signal "L2")
		(6 "In2.Cu" signal "L3")
		(8 "In3.Cu" signal "L4")
		(10 "In4.Cu" signal "L5")
		(12 "In5.Cu" signal "L6")
		(14 "In6.Cu" signal "L7")
		(16 "In7.Cu" signal "L8")
		(18 "In8.Cu" signal "L9")
		(20 "In9.Cu" signal "L10")
		(22 "In10.Cu" signal "L11")
		(2 "B.Cu" signal "BOTTOM")
		(9 "F.Adhes" user "F.Adhesive")
		(11 "B.Adhes" user "B.Adhesive")
		(13 "F.Paste" user "Package Geometry/Pastemask Top")
		(15 "B.Paste" user "Package Geometry/Pastemask Bottom")
		(5 "F.SilkS" user "Ref Des/Silkscreen Top")
		(7 "B.SilkS" user "Ref Des/Silkscreen Bottom")
		(1 "F.Mask" user "Board Geometry/Soldermask Top")
		(3 "B.Mask" user "Board Geometry/Soldermask Bottom")
		(17 "Dwgs.User" user "User.Drawings")
		(19 "Cmts.User" user "User.Comments")
		(21 "Eco1.User" user "User.Eco1")
		(23 "Eco2.User" user "User.Eco2")
		(25 "Edge.Cuts" user "Board Geometry/Outline")
		(27 "Margin" user)
		(31 "F.CrtYd" user "Package Geometry/Place Bound Top")
		(29 "B.CrtYd" user "Package Geometry/Place Bound Bottom")
		(35 "F.Fab" user "Ref Des/Assembly Top")
		(33 "B.Fab" user "Ref Des/Assembly Bottom")
	)
	(footprint ""
		(layer "F.Cu")
		(at 53.213 -23.495 90)
		(property "Reference" "R455"
			(at 0 0 90)
			(layer "F.SilkS")
			(hide yes)
			(effects
				(font
					(size 1.27 1.27)
				)
			)
		)
		(property "Value" "4K7R2F-GP"
			(at 1.7907 -1.1176 90)
			(unlocked yes)
			(layer "F.Fab")
			(hide yes)
			(effects
				(font
					(size 1.016 1.016)
					(thickness 0.1524)
				)
			)
		)
		(property "Device Type" "R402H16"
			(at 1.7907 -2.6416 90)
			(unlocked yes)
			(layer "F.Fab")
			(hide yes)
			(effects
				(font
					(size 1.016 1.016)
					(thickness 0.1524)
				)
			)
		)
		(duplicate_pad_numbers_are_jumpers no)
		(fp_rect
			(start -0.381 0.8382)
			(end 0.381 -0.8382)
			(stroke
				(width 0)
				(type default)
			)
			(fill no)
			(layer "F.CrtYd")
		)
		(fp_rect
			(start -0.381 0.8382)
			(end 0.381 -0.8382)
			(stroke
				(width 0)
				(type default)
			)
			(fill no)
			(layer "F.Fab")
		)
		(pad "1" smd custom
			(at 0 -0.4318 90)
			(size 0.127 0.127)
			(layers "F.Cu" "F.Mask" "F.Paste")
			(net "CLKBUFF_OE4#")
			(options
				(clearance outline)
				(anchor circle)
			)
			(primitives
				(gr_poly
					(pts
						(arc
							(start -0.2032 -0.2794)
							(mid -0.239121 -0.264521)
							(end -0.254 -0.2286)
						)
						(arc
							(start -0.254 0.2286)
							(mid -0.239121 0.264521)
							(end -0.2032 0.2794)
						)
						(arc
							(start 0.2032 0.2794)
							(mid 0.239121 0.264521)
							(end 0.254 0.2286)
						)
						(arc
							(start 0.254 -0.2286)
							(mid 0.239121 -0.264521)
							(end 0.2032 -0.2794)
						)
					)
					(width 0)
					(fill yes)
				)
			)
		)
		(pad "2" smd custom
			(at 0 0.4318 90)
			(size 0.127 0.127)
			(layers "F.Cu" "F.Mask" "F.Paste")
			(net "GND")
			(options
				(clearance outline)
				(anchor circle)
			)
			(primitives
				(gr_poly
					(pts
						(arc
							(start -0.2032 -0.2794)
							(mid -0.239121 -0.264521)
							(end -0.254 -0.2286)
						)
						(arc
							(start -0.254 0.2286)
							(mid -0.239121 0.264521)
							(end -0.2032 0.2794)
						)
						(arc
							(start 0.2032 0.2794)
							(mid 0.239121 0.264521)
							(end 0.254 0.2286)
						)
						(arc
							(start 0.254 -0.2286)
							(mid 0.239121 -0.264521)
							(end 0.2032 -0.2794)
						)
					)
					(width 0)
					(fill yes)
				)
			)
		)
	)
	(footprint ""
		(layer "F.Cu")
		(at 158.5214 -45.339 90)
		(property "Reference" "R214"
			(at 0 0 90)
			(layer "F.SilkS")
			(hide yes)
			(effects
				(font
					(size 1.27 1.27)
				)
			)
		)
		(property "Value" "10KR2F-2-GP"
			(at 1.7907 -1.1176 90)
			(unlocked yes)
			(layer "F.Fab")
			(hide yes)
			(effects
				(font
					(size 1.016 1.016)
					(thickness 0.1524)
				)
			)
		)
		(property "Device Type" "R402H16"
			(at 1.7907 -2.6416 90)
			(unlocked yes)
			(layer "F.Fab")
			(hide yes)
			(effects
				(font
					(size 1.016 1.016)
					(thickness 0.1524)
				)
			)
		)
		(duplicate_pad_numbers_are_jumpers no)
		(fp_rect
			(start -0.381 0.8382)
			(end 0.381 -0.8382)
			(stroke
				(width 0)
				(type default)
			)
			(fill no)
			(layer "F.CrtYd")
		)
		(fp_rect
			(start -0.381 0.8382)
			(end 0.381 -0.8382)
			(stroke
				(width 0)
				(type default)
			)
			(fill no)
			(layer "F.Fab")
		)
		(pad "1" smd custom
			(at 0 -0.4318 90)
			(size 0.127 0.127)
			(layers "F.Cu" "F.Mask" "F.Paste")
			(net "P3V3_CPU")
			(options
				(clearance outline)
				(anchor circle)
			)
			(primitives
				(gr_poly
					(pts
						(arc
							(start -0.2032 -0.2794)
							(mid -0.239121 -0.264521)
							(end -0.254 -0.2286)
						)
						(arc
							(start -0.254 0.2286)
							(mid -0.239121 0.264521)
							(end -0.2032 0.2794)
						)
						(arc
							(start 0.2032 0.2794)
							(mid 0.239121 0.264521)
							(end 0.254 0.2286)
						)
						(arc
							(start 0.254 -0.2286)
							(mid 0.239121 -0.264521)
							(end 0.2032 -0.2794)
						)
					)
					(width 0)
					(fill yes)
				)
			)
		)
		(pad "2" smd custom
			(at 0 0.4318 90)
			(size 0.127 0.127)
			(layers "F.Cu" "F.Mask" "F.Paste")
			(net "JTAG_CHAIN_EN")
			(options
				(clearance outline)
				(anchor circle)
			)
			(primitives
				(gr_poly
					(pts
						(arc
							(start -0.2032 -0.2794)
							(mid -0.239121 -0.264521)
							(end -0.254 -0.2286)
						)
						(arc
							(start -0.254 0.2286)
							(mid -0.239121 0.264521)
							(end -0.2032 0.2794)
						)
						(arc
							(start 0.2032 0.2794)
							(mid 0.239121 0.264521)
							(end 0.254 0.2286)
						)
						(arc
							(start 0.254 -0.2286)
							(mid 0.239121 -0.264521)
							(end 0.2032 -0.2794)
						)
					)
					(width 0)
					(fill yes)
				)
			)
		)
	)
	(footprint ""
		(layer "F.Cu")
		(at 184.912 -39.878 180)
		(property "Reference" "PR121"
			(at 0 0 180)
			(layer "F.SilkS")
			(hide yes)
			(effects
				(font
					(size 1.27 1.27)
				)
			)
		)
		(property "Value" "787R2F-GP"
			(at 1.7907 -1.1176 180)
			(unlocked yes)
			(layer "F.Fab")
			(hide yes)
			(effects
				(font
					(size 1.016 1.016)
					(thickness 0.1524)
				)
			)
		)
		(property "Device Type" "R402H16"
			(at 1.7907 -2.6416 180)
			(unlocked yes)
			(layer "F.Fab")
			(hide yes)
			(effects
				(font
					(size 1.016 1.016)
					(thickness 0.1524)
				)
			)
		)
		(duplicate_pad_numbers_are_jumpers no)
		(fp_rect
			(start -0.381 0.8382)
			(end 0.381 -0.8382)
			(stroke
				(width 0)
				(type default)
			)
			(fill no)
			(layer "F.CrtYd")
		)
		(fp_rect
			(start -0.381 0.8382)
			(end 0.381 -0.8382)
			(stroke
				(width 0)
				(type default)
			)
			(fill no)
			(layer "F.Fab")
		)
		(pad "1" smd custom
			(at 0 -0.4318 180)
			(size 0.127 0.127)
			(layers "F.Cu" "F.Mask" "F.Paste")
			(net "VR_PVDDR_A_SVID_ADDR")
			(options
				(clearance outline)
				(anchor circle)
			)
			(primitives
				(gr_poly
					(pts
						(arc
							(start -0.2032 -0.2794)
							(mid -0.239121 -0.264521)
							(end -0.254 -0.2286)
						)
						(arc
							(start -0.254 0.2286)
							(mid -0.239121 0.264521)
							(end -0.2032 0.2794)
						)
						(arc
							(start 0.2032 0.2794)
							(mid 0.239121 0.264521)
							(end 0.254 0.2286)
						)
						(arc
							(start 0.254 -0.2286)
							(mid 0.239121 -0.264521)
							(end 0.2032 -0.2794)
						)
					)
					(width 0)
					(fill yes)
				)
			)
		)
		(pad "2" smd custom
			(at 0 0.4318 180)
			(size 0.127 0.127)
			(layers "F.Cu" "F.Mask" "F.Paste")
			(net "GND")
			(options
				(clearance outline)
				(anchor circle)
			)
			(primitives
				(gr_poly
					(pts
						(arc
							(start -0.2032 -0.2794)
							(mid -0.239121 -0.264521)
							(end -0.254 -0.2286)
						)
						(arc
							(start -0.254 0.2286)
							(mid -0.239121 0.264521)
							(end -0.2032 0.2794)
						)
						(arc
							(start 0.2032 0.2794)
							(mid 0.239121 0.264521)
							(end 0.254 0.2286)
						)
						(arc
							(start 0.254 -0.2286)
							(mid 0.239121 -0.264521)
							(end 0.2032 -0.2794)
						)
					)
					(width 0)
					(fill yes)
				)
			)
		)
	)
	(footprint ""
		(layer "F.Cu")
		(at 62.738 -23.241 -90)
		(property "Reference" "R256"
			(at 0 0 270)
			(layer "F.SilkS")
			(hide yes)
			(effects
				(font
					(size 1.27 1.27)
				)
			)
		)
		(property "Value" "4K02R2F-GP"
			(at 0.064008 -3.993896 270)
			(unlocked yes)
			(layer "F.Fab")
			(hide yes)
			(effects
				(font
					(size 1.016 1.016)
					(thickness 0.1524)
				)
			)
		)
		(property "Device Type" "R402H16"
			(at 0.064008 -5.517896 270)
			(unlocked yes)
			(layer "F.Fab")
			(hide yes)
			(effects
				(font
					(size 1.016 1.016)
					(thickness 0.1524)
				)
			)
		)
		(duplicate_pad_numbers_are_jumpers no)
		(fp_rect
			(start -0.381 0.8382)
			(end 0.381 -0.8382)
			(stroke
				(width 0)
				(type default)
			)
			(fill no)
			(layer "F.CrtYd")
		)
		(fp_rect
			(start -0.381 0.8382)
			(end 0.381 -0.8382)
			(stroke
				(width 0)
				(type default)
			)
			(fill no)
			(layer "F.Fab")
		)
		(pad "1" smd custom
			(at 0 -0.4318 270)
			(size 0.127 0.127)
			(layers "F.Cu" "F.Mask" "F.Paste")
			(net "SW_P1V8_EN_S")
			(options
				(clearance outline)
				(anchor circle)
			)
			(primitives
				(gr_poly
					(pts
						(arc
							(start -0.2032 -0.2794)
							(mid -0.239121 -0.264521)
							(end -0.254 -0.2286)
						)
						(arc
							(start -0.254 0.2286)
							(mid -0.239121 0.264521)
							(end -0.2032 0.2794)
						)
						(arc
							(start 0.2032 0.2794)
							(mid 0.239121 0.264521)
							(end 0.254 0.2286)
						)
						(arc
							(start 0.254 -0.2286)
							(mid 0.239121 -0.264521)
							(end 0.2032 -0.2794)
						)
					)
					(width 0)
					(fill yes)
				)
			)
		)
		(pad "2" smd custom
			(at 0 0.4318 270)
			(size 0.127 0.127)
			(layers "F.Cu" "F.Mask" "F.Paste")
			(net "P3V3_STBY")
			(options
				(clearance outline)
				(anchor circle)
			)
			(primitives
				(gr_poly
					(pts
						(arc
							(start -0.2032 -0.2794)
							(mid -0.239121 -0.264521)
							(end -0.254 -0.2286)
						)
						(arc
							(start -0.254 0.2286)
							(mid -0.239121 0.264521)
							(end -0.2032 0.2794)
						)
						(arc
							(start 0.2032 0.2794)
							(mid 0.239121 0.264521)
							(end 0.254 0.2286)
						)
						(arc
							(start 0.254 -0.2286)
							(mid 0.239121 -0.264521)
							(end 0.2032 -0.2794)
						)
					)
					(width 0)
					(fill yes)
				)
			)
		)
	)
	(footprint ""
		(layer "F.Cu")
		(at 39.751 -15.494 -90)
		(property "Reference" "C39"
			(at 0 0 270)
			(layer "F.SilkS")
			(hide yes)
			(effects
				(font
					(size 1.27 1.27)
				)
			)
		)
		(property "Value" "SC10U25V5KX-GP"
			(at 0 -4.9022 270)
			(unlocked yes)
			(layer "F.Fab")
			(hide yes)
			(effects
				(font
					(size 1.016 1.016)
					(thickness 0.1524)
				)
			)
		)
		(property "Device Type" "C805H56"
			(at 0 -6.8072 270)
			(unlocked yes)
			(layer "F.Fab")
			(hide yes)
			(effects
				(font
					(size 1.016 1.016)
					(thickness 0.1524)
				)
			)
		)
		(duplicate_pad_numbers_are_jumpers no)
		(fp_line
			(start 0.6096 0)
			(end -0.6096 0)
			(stroke
				(width 0.3048)
				(type default)
			)
			(layer "F.SilkS")
		)
		(fp_poly
			(pts
				(xy -0.9017 1.4351) (xy 0.9017 1.4351) (xy 0.9017 -1.4351) (xy -0.9017 -1.4351)
			)
			(stroke
				(width 0)
				(type default)
			)
			(fill no)
			(layer "F.CrtYd")
		)
		(fp_poly
			(pts
				(xy 0.9017 1.4351) (xy 0.9017 -1.4351) (xy -0.9017 -1.4351) (xy -0.9017 1.4351)
			)
			(stroke
				(width 0)
				(type default)
			)
			(fill no)
			(layer "F.Fab")
		)
		(pad "1" smd rect
			(at 0 -0.8382 270)
			(size 1.5494 0.9398)
			(layers "F.Cu" "F.Mask" "F.Paste")
			(net "P3V3_VDD_CLKBUFF")
		)
		(pad "2" smd rect
			(at 0 0.8382 270)
			(size 1.5494 0.9398)
			(layers "F.Cu" "F.Mask" "F.Paste")
			(net "GND")
		)
	)
	(footprint ""
		(layer "F.Cu")
		(at 62.738 -22.479 -90)
		(property "Reference" "R257"
			(at 0 0 270)
			(layer "F.SilkS")
			(hide yes)
			(effects
				(font
					(size 1.27 1.27)
				)
			)
		)
		(property "Value" "0R2J-2-GP"
			(at 0.064008 -3.993896 270)
			(unlocked yes)
			(layer "F.Fab")
			(hide yes)
			(effects
				(font
					(size 1.016 1.016)
					(thickness 0.1524)
				)
			)
		)
		(property "Device Type" "R402H16"
			(at 0.064008 -5.517896 270)
			(unlocked yes)
			(layer "F.Fab")
			(hide yes)
			(effects
				(font
					(size 1.016 1.016)
					(thickness 0.1524)
				)
			)
		)
		(duplicate_pad_numbers_are_jumpers no)
		(fp_rect
			(start -0.381 0.8382)
			(end 0.381 -0.8382)
			(stroke
				(width 0)
				(type default)
			)
			(fill no)
			(layer "F.CrtYd")
		)
		(fp_rect
			(start -0.381 0.8382)
			(end 0.381 -0.8382)
			(stroke
				(width 0)
				(type default)
			)
			(fill no)
			(layer "F.Fab")
		)
		(pad "1" smd custom
			(at 0 -0.4318 270)
			(size 0.127 0.127)
			(layers "F.Cu" "F.Mask" "F.Paste")
			(net "SW_P1V8_EN_S")
			(options
				(clearance outline)
				(anchor circle)
			)
			(primitives
				(gr_poly
					(pts
						(arc
							(start -0.2032 -0.2794)
							(mid -0.239121 -0.264521)
							(end -0.254 -0.2286)
						)
						(arc
							(start -0.254 0.2286)
							(mid -0.239121 0.264521)
							(end -0.2032 0.2794)
						)
						(arc
							(start 0.2032 0.2794)
							(mid 0.239121 0.264521)
							(end 0.254 0.2286)
						)
						(arc
							(start 0.254 -0.2286)
							(mid 0.239121 -0.264521)
							(end 0.2032 -0.2794)
						)
					)
					(width 0)
					(fill yes)
				)
			)
		)
		(pad "2" smd custom
			(at 0 0.4318 270)
			(size 0.127 0.127)
			(layers "F.Cu" "F.Mask" "F.Paste")
			(net "PWRGD_P1V0_PG")
			(options
				(clearance outline)
				(anchor circle)
			)
			(primitives
				(gr_poly
					(pts
						(arc
							(start -0.2032 -0.2794)
							(mid -0.239121 -0.264521)
							(end -0.254 -0.2286)
						)
						(arc
							(start -0.254 0.2286)
							(mid -0.239121 0.264521)
							(end -0.2032 0.2794)
						)
						(arc
							(start 0.2032 0.2794)
							(mid 0.239121 0.264521)
							(end 0.254 0.2286)
						)
						(arc
							(start 0.254 -0.2286)
							(mid 0.239121 -0.264521)
							(end 0.2032 -0.2794)
						)
					)
					(width 0)
					(fill yes)
				)
			)
		)
	)
	(footprint ""
		(layer "F.Cu")
		(at 138.176 -20.574)
		(property "Reference" "TP12"
			(at 0 0 0)
			(layer "F.SilkS")
			(hide yes)
			(effects
				(font
					(size 1.27 1.27)
				)
			)
		)
		(property "Value" "TPAD28-1-GP-U"
			(at 0.0508 -1.9304 0)
			(unlocked yes)
			(layer "F.Fab")
			(hide yes)
			(effects
				(font
					(size 1.016 1.016)
					(thickness 0.1524)
				)
			)
		)
		(property "Device Type" "TPAD28-1-U"
			(at 0.0508 -3.4544 0)
			(unlocked yes)
			(layer "F.Fab")
			(hide yes)
			(effects
				(font
					(size 1.016 1.016)
					(thickness 0.1524)
				)
			)
		)
		(duplicate_pad_numbers_are_jumpers no)
		(fp_poly
			(pts
				(arc
					(start 0.3556 0)
					(mid -0.3556 0)
					(end 0.3556 0)
				)
			)
			(stroke
				(width 0)
				(type default)
			)
			(fill no)
			(layer "F.CrtYd")
		)
		(fp_poly
			(pts
				(arc
					(start 0.9525 0)
					(mid -0.9525 0)
					(end 0.9525 0)
				)
			)
			(stroke
				(width 0)
				(type default)
			)
			(fill no)
			(layer "F.Fab")
		)
		(pad "1" smd circle
			(at 0 0)
			(size 0.7112 0.7112)
			(layers "F.Cu" "F.Mask" "F.Paste")
			(net "TP_FPGA_P84")
		)
	)
	(footprint ""
		(layer "F.Cu")
		(at 64.897 -24.13 180)
		(property "Reference" "R250"
			(at 0 0 180)
			(layer "F.SilkS")
			(hide yes)
			(effects
				(font
					(size 1.27 1.27)
				)
			)
		)
		(property "Value" "10KR2F-2-GP"
			(at 0.064008 -3.993896 180)
			(unlocked yes)
			(layer "F.Fab")
			(hide yes)
			(effects
				(font
					(size 1.016 1.016)
					(thickness 0.1524)
				)
			)
		)
		(property "Device Type" "R402H16"
			(at 0.064008 -5.517896 180)
			(unlocked yes)
			(layer "F.Fab")
			(hide yes)
			(effects
				(font
					(size 1.016 1.016)
					(thickness 0.1524)
				)
			)
		)
		(duplicate_pad_numbers_are_jumpers no)
		(fp_rect
			(start -0.381 0.8382)
			(end 0.381 -0.8382)
			(stroke
				(width 0)
				(type default)
			)
			(fill no)
			(layer "F.CrtYd")
		)
		(fp_rect
			(start -0.381 0.8382)
			(end 0.381 -0.8382)
			(stroke
				(width 0)
				(type default)
			)
			(fill no)
			(layer "F.Fab")
		)
		(pad "1" smd custom
			(at 0 -0.4318 180)
			(size 0.127 0.127)
			(layers "F.Cu" "F.Mask" "F.Paste")
			(net "P12V")
			(options
				(clearance outline)
				(anchor circle)
			)
			(primitives
				(gr_poly
					(pts
						(arc
							(start -0.2032 -0.2794)
							(mid -0.239121 -0.264521)
							(end -0.254 -0.2286)
						)
						(arc
							(start -0.254 0.2286)
							(mid -0.239121 0.264521)
							(end -0.2032 0.2794)
						)
						(arc
							(start 0.2032 0.2794)
							(mid 0.239121 0.264521)
							(end 0.254 0.2286)
						)
						(arc
							(start 0.254 -0.2286)
							(mid 0.239121 -0.264521)
							(end 0.2032 -0.2794)
						)
					)
					(width 0)
					(fill yes)
				)
			)
		)
		(pad "2" smd custom
			(at 0 0.4318 180)
			(size 0.127 0.127)
			(layers "F.Cu" "F.Mask" "F.Paste")
			(net "SW_P1V8_EN_LV")
			(options
				(clearance outline)
				(anchor circle)
			)
			(primitives
				(gr_poly
					(pts
						(arc
							(start -0.2032 -0.2794)
							(mid -0.239121 -0.264521)
							(end -0.254 -0.2286)
						)
						(arc
							(start -0.254 0.2286)
							(mid -0.239121 0.264521)
							(end -0.2032 0.2794)
						)
						(arc
							(start 0.2032 0.2794)
							(mid 0.239121 0.264521)
							(end 0.254 0.2286)
						)
						(arc
							(start 0.254 -0.2286)
							(mid 0.239121 -0.264521)
							(end 0.2032 -0.2794)
						)
					)
					(width 0)
					(fill yes)
				)
			)
		)
	)
	(footprint ""
		(layer "F.Cu")
		(at 169.7228 -46.736 90)
		(property "Reference" "R401"
			(at 0 0 90)
			(layer "F.SilkS")
			(hide yes)
			(effects
				(font
					(size 1.27 1.27)
				)
			)
		)
		(property "Value" "10KR2F-2-GP"
			(at 1.7907 -1.1176 90)
			(unlocked yes)
			(layer "F.Fab")
			(hide yes)
			(effects
				(font
					(size 1.016 1.016)
					(thickness 0.1524)
				)
			)
		)
		(property "Device Type" "R402H16"
			(at 1.7907 -2.6416 90)
			(unlocked yes)
			(layer "F.Fab")
			(hide yes)
			(effects
				(font
					(size 1.016 1.016)
					(thickness 0.1524)
				)
			)
		)
		(duplicate_pad_numbers_are_jumpers no)
		(fp_rect
			(start -0.381 0.8382)
			(end 0.381 -0.8382)
			(stroke
				(width 0)
				(type default)
			)
			(fill no)
			(layer "F.CrtYd")
		)
		(fp_rect
			(start -0.381 0.8382)
			(end 0.381 -0.8382)
			(stroke
				(width 0)
				(type default)
			)
			(fill no)
			(layer "F.Fab")
		)
		(pad "1" smd custom
			(at 0 -0.4318 90)
			(size 0.127 0.127)
			(layers "F.Cu" "F.Mask" "F.Paste")
			(net "JTAG_CHAIN_EN")
			(options
				(clearance outline)
				(anchor circle)
			)
			(primitives
				(gr_poly
					(pts
						(arc
							(start -0.2032 -0.2794)
							(mid -0.239121 -0.264521)
							(end -0.254 -0.2286)
						)
						(arc
							(start -0.254 0.2286)
							(mid -0.239121 0.264521)
							(end -0.2032 0.2794)
						)
						(arc
							(start 0.2032 0.2794)
							(mid 0.239121 0.264521)
							(end 0.254 0.2286)
						)
						(arc
							(start 0.254 -0.2286)
							(mid 0.239121 -0.264521)
							(end 0.2032 -0.2794)
						)
					)
					(width 0)
					(fill yes)
				)
			)
		)
		(pad "2" smd custom
			(at 0 0.4318 90)
			(size 0.127 0.127)
			(layers "F.Cu" "F.Mask" "F.Paste")
			(net "GND")
			(options
				(clearance outline)
				(anchor circle)
			)
			(primitives
				(gr_poly
					(pts
						(arc
							(start -0.2032 -0.2794)
							(mid -0.239121 -0.264521)
							(end -0.254 -0.2286)
						)
						(arc
							(start -0.254 0.2286)
							(mid -0.239121 0.264521)
							(end -0.2032 0.2794)
						)
						(arc
							(start 0.2032 0.2794)
							(mid 0.239121 0.264521)
							(end 0.254 0.2286)
						)
						(arc
							(start 0.254 -0.2286)
							(mid 0.239121 -0.264521)
							(end 0.2032 -0.2794)
						)
					)
					(width 0)
					(fill yes)
				)
			)
		)
	)
)
